(kicad_pcb
	(version 20221018)
	(generator pcbnew)
	(general
    (thickness 1.7403)
  )
	(paper "A4")
	(title_block
    (title "Data Center RDIMM DDR4 Tester")
    (date "2024-09-30")
    (rev "1.2.4")
		(comment 9 "footprints 87-91 of 690")
	)
	(layers
    (0 "F.Cu" signal)
    (1 "In1.Cu" power)
    (2 "In2.Cu" signal)
    (3 "In3.Cu" power)
    (4 "In4.Cu" power)
    (5 "In5.Cu" signal)
    (6 "In6.Cu" power)
    (7 "In7.Cu" signal)
    (8 "In8.Cu" power)
    (9 "In9.Cu" signal)
    (10 "In10.Cu" power)
    (31 "B.Cu" signal)
    (32 "B.Adhes" user "B.Adhesive")
    (33 "F.Adhes" user "F.Adhesive")
    (34 "B.Paste" user)
    (35 "F.Paste" user)
    (36 "B.SilkS" user "B.Silkscreen")
    (37 "F.SilkS" user "F.Silkscreen")
    (38 "B.Mask" user)
    (39 "F.Mask" user)
    (40 "Dwgs.User" user "User.Drawings")
    (41 "Cmts.User" user "User.Comments")
    (42 "Eco1.User" user "User.Eco1")
    (43 "Eco2.User" user "User.Eco2")
    (44 "Edge.Cuts" user)
    (45 "Margin" user)
    (46 "B.CrtYd" user "B.Courtyard")
    (47 "F.CrtYd" user "F.Courtyard")
    (48 "B.Fab" user)
    (49 "F.Fab" user)
  )
	(footprint "data-center-rdimm-ddr4-tester-footprints:C_0402_1005Metric" (layer "F.Cu")
    (at 133.936328 103.752157 180)
    (descr "Capacitor SMD 0402")
    (tags "capacitor SMD 0402")
    (property "Author" "Antmicro")
    (property "Dielectric" "X5R")
    (property "License" "Apache-2.0")
    (property "MPN" "GRM155R61H104KE14D")
    (property "Manufacturer" "Murata")
    (property "Sheetfile" "interfaces.kicad_sch")
    (property "Sheetname" "Interfaces")
    (property "Val" "100n")
    (property "Voltage" "50V")
    (property "ki_description" " ")
    (attr smd)
    (fp_text reference "C197" (at 3.706328 -0.377843 180) (layer "F.SilkS")
        (effects (font (size 0.7 0.7) (thickness 0.15)) (justify left bottom))
    )
    (fp_text value "C_100n_0402" (at 0 1.4 180) (layer "F.Fab") hide
        (effects (font (size 0.7 0.7) (thickness 0.15)) (justify left bottom))
    )
    (fp_text user "${REFERENCE}" (at -0.932 3.168 180) (layer "F.Fab") hide
        (effects (font (size 0.7 0.7) (thickness 0.15)) (justify left bottom))
    )
    (fp_text user "License: Apache-2.0" (at -0.932 5.17 180) (layer "F.Fab") hide
        (effects (font (size 0.7 0.7) (thickness 0.15)) (justify left bottom))
    )
    (fp_text user "Author: Antmicro" (at -0.932 4.17 180) (layer "F.Fab") hide
        (effects (font (size 0.7 0.7) (thickness 0.15)) (justify left bottom))
    )
    (fp_rect (start -0.94 -0.47) (end 0.94 0.47)
      (stroke (width 0.05) (type solid)) (fill none) (layer "F.CrtYd"))
    (fp_rect (start -0.499 -0.249) (end 0.499 0.249)
      (stroke (width 0.15) (type solid)) (fill none) (layer "F.Fab"))
    (pad "1" smd roundrect (at -0.484 0 180) (size 0.59 0.64) (layers "F.Cu" "F.Paste" "F.Mask") (roundrect_rratio 0.25)
      (net 145 "1V8_FT") (pintype "passive"))
    (pad "2" smd roundrect (at 0.484 0 180) (size 0.59 0.64) (layers "F.Cu" "F.Paste" "F.Mask") (roundrect_rratio 0.25)
      (net 9 "GND") (pintype "passive"))
  )
	(footprint "data-center-rdimm-ddr4-tester-footprints:R_0402_1005Metric" (layer "F.Cu")
    (at 118.711328 96.285008 90)
    (descr "Resistor SMD 0402")
    (tags "resistor SMD 0402")
    (property "Author" "Antmicro")
    (property "License" "Apache-2.0")
    (property "MPN" "CR0402-FX-5R10GLF")
    (property "Manufacturer" "Bourns")
    (property "Sheetfile" "supply.kicad_sch")
    (property "Sheetname" "Supply")
    (property "Tolerance" "1%")
    (property "Val" "5R1")
    (property "ki_description" "5R1 resistor in 0402 package with 1% tolerance")
    (attr smd)
    (fp_text reference "R35" (at -1.064992 -0.511328 90) (layer "F.SilkS")
        (effects (font (size 0.7 0.7) (thickness 0.15)) (justify left bottom))
    )
    (fp_text value "R_5R1_0402" (at 0 1.4 90) (layer "F.Fab") hide
        (effects (font (size 0.7 0.7) (thickness 0.15)) (justify left bottom))
    )
    (fp_text user "License: Apache-2.0" (at -0.95 5.169 90) (layer "F.Fab") hide
        (effects (font (size 0.7 0.7) (thickness 0.15)) (justify left bottom))
    )
    (fp_text user "Author: Antmicro" (at -0.95 4.169 90) (layer "F.Fab") hide
        (effects (font (size 0.7 0.7) (thickness 0.15)) (justify left bottom))
    )
    (fp_text user "${REFERENCE}" (at -0.95 3.168 90) (layer "F.Fab") hide
        (effects (font (size 0.7 0.7) (thickness 0.15)) (justify left bottom))
    )
    (fp_rect (start -0.93 -0.47) (end 0.93 0.47)
      (stroke (width 0.05) (type solid)) (fill none) (layer "F.CrtYd"))
    (fp_rect (start -0.5 -0.25) (end 0.5 0.25)
      (stroke (width 0.15) (type solid)) (fill none) (layer "F.Fab"))
    (pad "1" smd roundrect (at -0.485 0 90) (size 0.59 0.64) (layers "F.Cu" "F.Paste" "F.Mask") (roundrect_rratio 0.25)
      (net 601 "Net-(U2-BST)") (pintype "passive"))
    (pad "2" smd roundrect (at 0.485 0 90) (size 0.59 0.64) (layers "F.Cu" "F.Paste" "F.Mask") (roundrect_rratio 0.25)
      (net 105 "Net-(C35-Pad1)") (pintype "passive"))
  )
	(footprint "data-center-rdimm-ddr4-tester-footprints:Testpoint_smd_1mm" (layer "F.Cu")
    (at 142.5 96.875)
    (property "Author" "Antmicro")
    (property "License" "Apache-2.0")
    (property "MPN" "")
    (property "Manufacturer" "")
    (property "Sheetfile" "supply.kicad_sch")
    (property "Sheetname" "Supply")
    (property "ki_description" "Test Point 1mm")
    (attr exclude_from_pos_files)
    (fp_text reference "TP8" (at 0.52 0.385) (layer "F.SilkS")
        (effects (font (size 0.7 0.7) (thickness 0.15)) (justify left bottom))
    )
    (fp_text value "TP_1mm_SMD" (at 0 1.4) (layer "F.Fab") hide
        (effects (font (size 0.7 0.7) (thickness 0.15)) (justify left bottom))
    )
    (fp_text user "${REFERENCE}" (at -0.5 2.8) (layer "F.Fab") hide
        (effects (font (size 0.7 0.7) (thickness 0.15)) (justify left bottom))
    )
    (fp_text user "License: Apache-2.0" (at -0.5 5.2) (layer "F.Fab") hide
        (effects (font (size 0.7 0.7) (thickness 0.15)) (justify left bottom))
    )
    (fp_text user "Author: Antmicro" (at -0.5 4) (layer "F.Fab") hide
        (effects (font (size 0.7 0.7) (thickness 0.15)) (justify left bottom))
    )
    (pad "1" smd circle (at 0 0) (size 1 1) (layers "F.Cu" "F.Mask")
      (net 153 "/Supply/VCC_IO_EN") (pinfunction "1") (pintype "passive"))
  )
	(footprint "data-center-rdimm-ddr4-tester-footprints:C_0402_1005Metric" (layer "F.Cu")
    (at 140.161328 100.212157 90)
    (descr "Capacitor SMD 0402")
    (tags "capacitor SMD 0402")
    (property "Author" "Antmicro")
    (property "Dielectric" "X5R")
    (property "License" "Apache-2.0")
    (property "MPN" "GRM155R61H104KE14D")
    (property "Manufacturer" "Murata")
    (property "Sheetfile" "interfaces.kicad_sch")
    (property "Sheetname" "Interfaces")
    (property "Val" "100n")
    (property "Voltage" "50V")
    (property "ki_description" " ")
    (attr smd)
    (fp_text reference "C192" (at -1.207843 -1.431328 90) (layer "F.SilkS")
        (effects (font (size 0.7 0.7) (thickness 0.15)) (justify left bottom))
    )
    (fp_text value "C_100n_0402" (at 0 1.4 90) (layer "F.Fab") hide
        (effects (font (size 0.7 0.7) (thickness 0.15)) (justify left bottom))
    )
    (fp_text user "License: Apache-2.0" (at -0.932 5.17 90) (layer "F.Fab") hide
        (effects (font (size 0.7 0.7) (thickness 0.15)) (justify left bottom))
    )
    (fp_text user "${REFERENCE}" (at -0.932 3.168 90) (layer "F.Fab") hide
        (effects (font (size 0.7 0.7) (thickness 0.15)) (justify left bottom))
    )
    (fp_text user "Author: Antmicro" (at -0.932 4.17 90) (layer "F.Fab") hide
        (effects (font (size 0.7 0.7) (thickness 0.15)) (justify left bottom))
    )
    (fp_rect (start -0.94 -0.47) (end 0.94 0.47)
      (stroke (width 0.05) (type solid)) (fill none) (layer "F.CrtYd"))
    (fp_rect (start -0.499 -0.249) (end 0.499 0.249)
      (stroke (width 0.15) (type solid)) (fill none) (layer "F.Fab"))
    (pad "1" smd roundrect (at -0.484 0 90) (size 0.59 0.64) (layers "F.Cu" "F.Paste" "F.Mask") (roundrect_rratio 0.25)
      (net 143 "3V3_SYS") (pintype "passive"))
    (pad "2" smd roundrect (at 0.484 0 90) (size 0.59 0.64) (layers "F.Cu" "F.Paste" "F.Mask") (roundrect_rratio 0.25)
      (net 9 "GND") (pintype "passive"))
  )
	(footprint "data-center-rdimm-ddr4-tester-footprints:PinHeader_1x3_P2.54mm_Drill1.1mm" (layer "F.Cu")
    (at 216.914328 120.547157 90)
    (property "Author" "Antmicro")
    (property "License" "Apache-2.0")
    (property "MPN" "61300311121")
    (property "Manufacturer" "Würth Elektronik")
    (property "Sheetfile" "supply.kicad_sch")
    (property "Sheetname" "Supply")
    (property "ki_description" "3x1 goldpin header")
    (property "ki_keywords" "3x1 goldpin header")
    (attr through_hole)
    (fp_text reference "J8" (at 6.755157 0.255672 180) (layer "F.SilkS")
        (effects (font (size 0.7 0.7) (thickness 0.15)) (justify left bottom))
    )
    (fp_text value "PinHeader_1x3_P2.54mm_Drill1.1mm" (at -1.6 2.7 90) (layer "F.Fab")
        (effects (font (size 0.7 0.7) (thickness 0.15)) (justify left bottom))
    )
    (fp_text user "License: Apache-2.0" (at -1.6 6.6 90) (layer "F.Fab") hide
        (effects (font (size 0.7 0.7) (thickness 0.15)) (justify left bottom))
    )
    (fp_text user "Author: Antmicro" (at -1.6 5.2 90) (layer "F.Fab") hide
        (effects (font (size 0.7 0.7) (thickness 0.15)) (justify left bottom))
    )
    (fp_text user "${REFERENCE}" (at -1.6 4 90) (layer "F.Fab") hide
        (effects (font (size 0.7 0.7) (thickness 0.15)) (justify left bottom))
    )
    (fp_line (start -1.401 -1.401) (end -1.401 -0.902)
      (stroke (width 0.15) (type solid)) (layer "F.SilkS"))
    (fp_line (start -1.401 -1.401) (end -0.902 -1.401)
      (stroke (width 0.15) (type solid)) (layer "F.SilkS"))
    (fp_line (start -1.401 1.398) (end -1.401 0.9)
      (stroke (width 0.15) (type solid)) (layer "F.SilkS"))
    (fp_line (start -1.401 1.398) (end -0.902 1.398)
      (stroke (width 0.15) (type solid)) (layer "F.SilkS"))
    (fp_line (start 6.499 -1.401) (end 5.999 -1.401)
      (stroke (width 0.15) (type solid)) (layer "F.SilkS"))
    (fp_line (start 6.499 -1.401) (end 6.499 -0.902)
      (stroke (width 0.15) (type solid)) (layer "F.SilkS"))
    (fp_line (start 6.499 1.398) (end 5.999 1.398)
      (stroke (width 0.15) (type solid)) (layer "F.SilkS"))
    (fp_line (start 6.499 1.398) (end 6.499 0.9)
      (stroke (width 0.15) (type solid)) (layer "F.SilkS"))
    (fp_line (start -1.52 -1.52) (end -1.52 1.5)
      (stroke (width 0.05) (type solid)) (layer "F.CrtYd"))
    (fp_line (start -1.52 -1.52) (end 6.58 -1.52)
      (stroke (width 0.05) (type solid)) (layer "F.CrtYd"))
    (fp_line (start -1.52 1.5) (end 6.58 1.5)
      (stroke (width 0.05) (type solid)) (layer "F.CrtYd"))
    (fp_line (start 6.58 -1.52) (end 6.58 1.5)
      (stroke (width 0.05) (type solid)) (layer "F.CrtYd"))
    (fp_line (start -1.27 -1.27) (end -1.27 1.269)
      (stroke (width 0.15) (type solid)) (layer "F.Fab"))
    (fp_line (start -1.27 -1.27) (end 6.349 -1.27)
      (stroke (width 0.15) (type solid)) (layer "F.Fab"))
    (fp_line (start -1.27 1.269) (end 6.349 1.269)
      (stroke (width 0.15) (type solid)) (layer "F.Fab"))
    (fp_line (start 6.349 -1.27) (end 6.349 1.269)
      (stroke (width 0.15) (type solid)) (layer "F.Fab"))
    (pad "1" thru_hole rect (at 0 0 90) (size 1.7 1.7) (drill 1.1) (layers "*.Cu" "*.Mask")
      (net 307 "5V0_SYS") (pintype "passive"))
    (pad "2" thru_hole circle (at 2.539 0 90) (size 1.7 1.7) (drill 1.1) (layers "*.Cu" "*.Mask")
      (net 383 "unconnected-(J8-Pad2)") (pintype "passive+no_connect"))
    (pad "3" thru_hole circle (at 5.078 0 90) (size 1.7 1.7) (drill 1.1) (layers "*.Cu" "*.Mask")
      (net 9 "GND") (pintype "passive"))
  )
)
